# SCM (Grand Teton) — schematic netlist excerpt (pin names and nets, part order shuffled) for the footprints in the layout excerpt that follows; sources: Cadence DE-HDL packaged netlist, KiCad conversion of 12092022_DA0F0TMDCD0_F0T_Management_Board_D_brd_V3_OCP.brd

C240  Q_CAP  0.1UF 25V 10% X7R  pkg 0402  page 52 : A = P3V3_AUX ; B = GND
C21  Q_CAP  0.01UF 50V 10% EMPTY  pkg C0402  page 12 : A = P0V6_DDR_VREF_AUX ; B = GND

(kicad_pcb
	(version 20260206)
	(generator "pcbnew")
	(generator_version "10.0")
	(general
		(thickness 1.6)
		(legacy_teardrops no)
	)
	(paper "A4")
	(title_block
		(title "12092022_DA0F0TMDCD0_F0T_Management_Board_D_brd_V3_OCP.brd")
		(comment 1 "Grand Teton / footprints 1306-1307 of 1440")
	)
	(layers
		(0 "F.Cu" signal "TOP")
		(4 "In1.Cu" signal "GND")
		(6 "In2.Cu" signal "IN1")
		(8 "In3.Cu" signal "GND1")
		(10 "In4.Cu" signal "IN2")
		(12 "In5.Cu" signal "VCC")
		(14 "In6.Cu" signal "VCC1")
		(16 "In7.Cu" signal "IN3")
		(18 "In8.Cu" signal "GND2")
		(20 "In9.Cu" signal "IN4")
		(22 "In10.Cu" signal "GND3")
		(2 "B.Cu" signal "BOTTOM")
		(9 "F.Adhes" user "F.Adhesive")
		(11 "B.Adhes" user "B.Adhesive")
		(13 "F.Paste" user "Package Geometry/Pastemask Top")
		(15 "B.Paste" user "Package Geometry/Pastemask Bottom")
		(5 "F.SilkS" user "Ref Des/Silkscreen Top")
		(7 "B.SilkS" user "Ref Des/Silkscreen Bottom")
		(1 "F.Mask" user "Board Geometry/Soldermask Top")
		(3 "B.Mask" user "Board Geometry/Soldermask Bottom")
		(17 "Dwgs.User" user "User.Drawings")
		(19 "Cmts.User" user "User.Comments")
		(21 "Eco1.User" user "User.Eco1")
		(23 "Eco2.User" user "User.Eco2")
		(25 "Edge.Cuts" user "Board Geometry/Outline")
		(27 "Margin" user)
		(31 "F.CrtYd" user "Package Geometry/Place Bound Top")
		(29 "B.CrtYd" user "Package Geometry/Place Bound Bottom")
		(35 "F.Fab" user "Ref Des/Assembly Top")
		(33 "B.Fab" user "Ref Des/Assembly Bottom")
	)
	(footprint ""
		(layer "B.Cu")
		(at 60.722256 -53.533548 -90)
		(property "Reference" "C21"
			(at 0 0 90)
			(layer "B.SilkS")
			(hide yes)
			(effects
				(font
					(size 1.27 1.27)
				)
				(justify mirror)
			)
		)
		(property "Value" ""
			(at 0 0 90)
			(layer "B.Fab")
			(effects
				(font
					(size 1.27 1.27)
				)
				(justify mirror)
			)
		)
		(duplicate_pad_numbers_are_jumpers no)
		(fp_line
			(start -0.7874 0.4064)
			(end 0.7874 0.4064)
			(stroke
				(width 0.1524)
				(type default)
			)
			(layer "B.SilkS")
		)
		(fp_line
			(start 0.7874 0.4064)
			(end 0.7874 -0.4064)
			(stroke
				(width 0.1524)
				(type default)
			)
			(layer "B.SilkS")
		)
		(fp_line
			(start -0.7874 -0.4064)
			(end -0.7874 0.4064)
			(stroke
				(width 0.1524)
				(type default)
			)
			(layer "B.SilkS")
		)
		(fp_line
			(start 0.7874 -0.4064)
			(end -0.7874 -0.4064)
			(stroke
				(width 0.1524)
				(type default)
			)
			(layer "B.SilkS")
		)
		(fp_line
			(start -0.67945 0.3048)
			(end -0.120396 0.3048)
			(stroke
				(width 0.1)
				(type default)
			)
			(layer "B.Fab")
		)
		(fp_line
			(start -0.120396 0.3048)
			(end -0.120396 0.2794)
			(stroke
				(width 0.1)
				(type default)
			)
			(layer "B.Fab")
		)
		(fp_line
			(start 0.12065 0.3048)
			(end 0.67945 0.3048)
			(stroke
				(width 0.1)
				(type default)
			)
			(layer "B.Fab")
		)
		(fp_line
			(start 0.67945 0.3048)
			(end 0.67945 -0.305054)
			(stroke
				(width 0.1)
				(type default)
			)
			(layer "B.Fab")
		)
		(fp_line
			(start -0.120396 0.2794)
			(end 0.12065 0.2794)
			(stroke
				(width 0.1)
				(type default)
			)
			(layer "B.Fab")
		)
		(fp_line
			(start 0.12065 0.2794)
			(end 0.12065 0.3048)
			(stroke
				(width 0.1)
				(type default)
			)
			(layer "B.Fab")
		)
		(fp_line
			(start -0.12065 -0.2794)
			(end -0.12065 -0.3048)
			(stroke
				(width 0.1)
				(type default)
			)
			(layer "B.Fab")
		)
		(fp_line
			(start 0.12065 -0.2794)
			(end -0.12065 -0.2794)
			(stroke
				(width 0.1)
				(type default)
			)
			(layer "B.Fab")
		)
		(fp_line
			(start -0.67945 -0.3048)
			(end -0.67945 0.3048)
			(stroke
				(width 0.1)
				(type default)
			)
			(layer "B.Fab")
		)
		(fp_line
			(start -0.12065 -0.3048)
			(end -0.67945 -0.3048)
			(stroke
				(width 0.1)
				(type default)
			)
			(layer "B.Fab")
		)
		(fp_line
			(start 0.12065 -0.305054)
			(end 0.12065 -0.2794)
			(stroke
				(width 0.1)
				(type default)
			)
			(layer "B.Fab")
		)
		(fp_line
			(start 0.67945 -0.305054)
			(end 0.12065 -0.305054)
			(stroke
				(width 0.1)
				(type default)
			)
			(layer "B.Fab")
		)
		(pad "1" smd circle
			(at 0.40005 0 90)
			(size 0 0)
			(layers "B.Cu" "B.Mask" "B.Paste")
			(net "P0V6_DDR_VREF_AUX")
		)
		(pad "2" smd circle
			(at -0.40005 0 90)
			(size 0 0)
			(layers "B.Cu" "B.Mask" "B.Paste")
			(net "GND")
		)
	)
	(footprint ""
		(layer "B.Cu")
		(at 69.997828 -30.8356 180)
		(property "Reference" "C240"
			(at 0 0 0)
			(layer "B.SilkS")
			(hide yes)
			(effects
				(font
					(size 1.27 1.27)
				)
				(justify mirror)
			)
		)
		(property "Value" ""
			(at 0 0 0)
			(layer "B.Fab")
			(effects
				(font
					(size 1.27 1.27)
				)
				(justify mirror)
			)
		)
		(duplicate_pad_numbers_are_jumpers no)
		(fp_line
			(start 0.7874 0.4064)
			(end 0.7874 -0.4064)
			(stroke
				(width 0.1524)
				(type default)
			)
			(layer "B.SilkS")
		)
		(fp_line
			(start 0.7874 -0.4064)
			(end -0.7874 -0.4064)
			(stroke
				(width 0.1524)
				(type default)
			)
			(layer "B.SilkS")
		)
		(fp_line
			(start -0.7874 0.4064)
			(end 0.7874 0.4064)
			(stroke
				(width 0.1524)
				(type default)
			)
			(layer "B.SilkS")
		)
		(fp_line
			(start -0.7874 -0.4064)
			(end -0.7874 0.4064)
			(stroke
				(width 0.1524)
				(type default)
			)
			(layer "B.SilkS")
		)
		(fp_line
			(start 0.67945 0.3048)
			(end 0.67945 -0.305054)
			(stroke
				(width 0.1)
				(type default)
			)
			(layer "B.Fab")
		)
		(fp_line
			(start 0.67945 -0.305054)
			(end 0.12065 -0.305054)
			(stroke
				(width 0.1)
				(type default)
			)
			(layer "B.Fab")
		)
		(fp_line
			(start 0.12065 0.3048)
			(end 0.67945 0.3048)
			(stroke
				(width 0.1)
				(type default)
			)
			(layer "B.Fab")
		)
		(fp_line
			(start 0.12065 0.2794)
			(end 0.12065 0.3048)
			(stroke
				(width 0.1)
				(type default)
			)
			(layer "B.Fab")
		)
		(fp_line
			(start 0.12065 -0.2794)
			(end -0.12065 -0.2794)
			(stroke
				(width 0.1)
				(type default)
			)
			(layer "B.Fab")
		)
		(fp_line
			(start 0.12065 -0.305054)
			(end 0.12065 -0.2794)
			(stroke
				(width 0.1)
				(type default)
			)
			(layer "B.Fab")
		)
		(fp_line
			(start -0.120396 0.3048)
			(end -0.120396 0.2794)
			(stroke
				(width 0.1)
				(type default)
			)
			(layer "B.Fab")
		)
		(fp_line
			(start -0.120396 0.2794)
			(end 0.12065 0.2794)
			(stroke
				(width 0.1)
				(type default)
			)
			(layer "B.Fab")
		)
		(fp_line
			(start -0.12065 -0.2794)
			(end -0.12065 -0.3048)
			(stroke
				(width 0.1)
				(type default)
			)
			(layer "B.Fab")
		)
		(fp_line
			(start -0.12065 -0.3048)
			(end -0.67945 -0.3048)
			(stroke
				(width 0.1)
				(type default)
			)
			(layer "B.Fab")
		)
		(fp_line
			(start -0.67945 0.3048)
			(end -0.120396 0.3048)
			(stroke
				(width 0.1)
				(type default)
			)
			(layer "B.Fab")
		)
		(fp_line
			(start -0.67945 -0.3048)
			(end -0.67945 0.3048)
			(stroke
				(width 0.1)
				(type default)
			)
			(layer "B.Fab")
		)
		(pad "1" smd circle
			(at 0.40005 0)
			(size 0 0)
			(layers "B.Cu" "B.Mask" "B.Paste")
			(net "P3V3_AUX")
		)
		(pad "2" smd circle
			(at -0.40005 0)
			(size 0 0)
			(layers "B.Cu" "B.Mask" "B.Paste")
			(net "GND")
		)
	)
)
